# T6G (Grand Teton) — schematic netlist excerpt (pin names and nets, part order shuffled) for the footprints in the layout excerpt that follows; sources: Cadence DE-HDL packaged netlist, KiCad conversion of 04192023_DAF0TMB3IC0_F0TG_MB_C_brd_V02_OCP.brd

PC391  Q_CAPP  220UF 4V 20% SPCAP  pkg SMLF  page 218 : A = PVDDCR_CPU1_P1 ; B = GND
C1079  Q_CAP  100PF 50V 5% EMPTY  pkg 0402  page 258 : A = P1V8_CPU0_RT_1D_ADC_MAM ; B = GND

(kicad_pcb
	(version 20260206)
	(generator "pcbnew")
	(generator_version "10.0")
	(general
		(thickness 1.6)
		(legacy_teardrops no)
	)
	(paper "A4")
	(title_block
		(title "04192023_DAF0TMB3IC0_F0TG_MB_C_brd_V02_OCP.brd")
		(comment 1 "Grand Teton / footprints 5314-5315 of 8354")
	)
	(layers
		(0 "F.Cu" signal "TOP")
		(4 "In1.Cu" signal "GND")
		(6 "In2.Cu" signal "IN1")
		(8 "In3.Cu" signal "GND1")
		(10 "In4.Cu" signal "IN2")
		(12 "In5.Cu" signal "GND2")
		(14 "In6.Cu" signal "IN3")
		(16 "In7.Cu" signal "GND3")
		(18 "In8.Cu" signal "VCC")
		(20 "In9.Cu" signal "VCC1")
		(22 "In10.Cu" signal "GND4")
		(24 "In11.Cu" signal "IN4")
		(26 "In12.Cu" signal "GND5")
		(28 "In13.Cu" signal "IN5")
		(30 "In14.Cu" signal "GND6")
		(32 "In15.Cu" signal "IN6")
		(34 "In16.Cu" signal "GND7")
		(2 "B.Cu" signal "BOTTOM")
		(9 "F.Adhes" user "F.Adhesive")
		(11 "B.Adhes" user "B.Adhesive")
		(13 "F.Paste" user "Package Geometry/Pastemask Top")
		(15 "B.Paste" user "Package Geometry/Pastemask Bottom")
		(5 "F.SilkS" user "Ref Des/Silkscreen Top")
		(7 "B.SilkS" user "Ref Des/Silkscreen Bottom")
		(1 "F.Mask" user "Board Geometry/Soldermask Top")
		(3 "B.Mask" user "Board Geometry/Soldermask Bottom")
		(17 "Dwgs.User" user "User.Drawings")
		(19 "Cmts.User" user "User.Comments")
		(21 "Eco1.User" user "User.Eco1")
		(23 "Eco2.User" user "User.Eco2")
		(25 "Edge.Cuts" user "Board Geometry/Outline")
		(27 "Margin" user)
		(31 "F.CrtYd" user "Package Geometry/Place Bound Top")
		(29 "B.CrtYd" user "Package Geometry/Place Bound Bottom")
		(35 "F.Fab" user "Ref Des/Assembly Top")
		(33 "B.Fab" user "Ref Des/Assembly Bottom")
	)
	(footprint ""
		(layer "B.Cu")
		(at 86.760304 -328.22388 -90)
		(property "Reference" "PC391"
			(at 9.533636 -0.911606 270)
			(unlocked yes)
			(layer "B.SilkS")
			(effects
				(font
					(size 0.7874 0.5842)
					(thickness 0.1524)
				)
				(justify left mirror)
			)
		)
		(property "Value" ""
			(at 0 0 90)
			(layer "B.Fab")
			(effects
				(font
					(size 1.27 1.27)
				)
				(justify mirror)
			)
		)
		(duplicate_pad_numbers_are_jumpers no)
		(fp_line
			(start -4.533392 2.249932)
			(end 4.533392 2.249932)
			(stroke
				(width 0.1524)
				(type default)
			)
			(layer "B.SilkS")
		)
		(fp_line
			(start 4.533392 2.249932)
			(end 4.533392 -2.249932)
			(stroke
				(width 0.1524)
				(type default)
			)
			(layer "B.SilkS")
		)
		(fp_line
			(start -4.533392 -2.249932)
			(end -4.533392 2.249932)
			(stroke
				(width 0.1524)
				(type default)
			)
			(layer "B.SilkS")
		)
		(fp_line
			(start 4.533392 -2.249932)
			(end -4.533392 -2.249932)
			(stroke
				(width 0.1524)
				(type default)
			)
			(layer "B.SilkS")
		)
		(fp_rect
			(start 5.39242 2.326132)
			(end 4.533392 -2.326132)
			(stroke
				(width 0)
				(type default)
			)
			(fill yes)
			(layer "B.SilkS")
		)
		(fp_line
			(start -3.750056 2.249932)
			(end 3.750056 2.249932)
			(stroke
				(width 0.1)
				(type default)
			)
			(layer "B.Fab")
		)
		(fp_line
			(start 3.750056 2.249932)
			(end 3.750056 -2.249932)
			(stroke
				(width 0.1)
				(type default)
			)
			(layer "B.Fab")
		)
		(fp_line
			(start -3.750056 -2.249932)
			(end -3.750056 2.249932)
			(stroke
				(width 0.1)
				(type default)
			)
			(layer "B.Fab")
		)
		(fp_line
			(start 3.750056 -2.249932)
			(end -3.750056 -2.249932)
			(stroke
				(width 0.1)
				(type default)
			)
			(layer "B.Fab")
		)
		(fp_text user "-"
			(at -4.562348 1.995932 270)
			(unlocked yes)
			(layer "B.SilkS")
			(effects
				(font
					(size 1.905 1.4224)
					(thickness 0.1524)
				)
				(justify left mirror)
			)
		)
		(fp_text user "+"
			(at 6.322314 0.786384 180)
			(unlocked yes)
			(layer "B.SilkS")
			(effects
				(font
					(size 1.905 1.4224)
					(thickness 0.1524)
				)
				(justify left mirror)
			)
		)
		(fp_text user "+"
			(at 6.322314 0.786384 180)
			(unlocked yes)
			(layer "B.Fab")
			(effects
				(font
					(size 1.905 1.4224)
					(thickness 0.1524)
				)
				(justify left mirror)
			)
		)
		(fp_text user "-"
			(at -4.8514 -0.14605 270)
			(unlocked yes)
			(layer "B.Fab")
			(effects
				(font
					(size 1.905 1.4224)
					(thickness 0.1524)
				)
				(justify left mirror)
			)
		)
		(pad "1" smd rect
			(at 3.199892 0 90)
			(size 2.413 2.8194)
			(layers "B.Cu" "B.Mask" "B.Paste")
			(net "PVDDCR_CPU1_P1")
		)
		(pad "2" smd rect
			(at -3.199892 0 90)
			(size 2.413 2.8194)
			(layers "B.Cu" "B.Mask" "B.Paste")
			(net "GND")
		)
	)
	(footprint ""
		(layer "B.Cu")
		(at 252.950726 -321.850004 180)
		(property "Reference" "C1079"
			(at 0 0 0)
			(layer "B.SilkS")
			(hide yes)
			(effects
				(font
					(size 1.27 1.27)
				)
				(justify mirror)
			)
		)
		(property "Value" ""
			(at 0 0 0)
			(layer "B.Fab")
			(effects
				(font
					(size 1.27 1.27)
				)
				(justify mirror)
			)
		)
		(duplicate_pad_numbers_are_jumpers no)
		(fp_line
			(start 0.7874 0.4064)
			(end 0.7874 -0.4064)
			(stroke
				(width 0.1524)
				(type default)
			)
			(layer "B.SilkS")
		)
		(fp_line
			(start 0.7874 -0.4064)
			(end -0.7874 -0.4064)
			(stroke
				(width 0.1524)
				(type default)
			)
			(layer "B.SilkS")
		)
		(fp_line
			(start -0.7874 0.4064)
			(end 0.7874 0.4064)
			(stroke
				(width 0.1524)
				(type default)
			)
			(layer "B.SilkS")
		)
		(fp_line
			(start -0.7874 -0.4064)
			(end -0.7874 0.4064)
			(stroke
				(width 0.1524)
				(type default)
			)
			(layer "B.SilkS")
		)
		(fp_line
			(start 0.67945 0.3048)
			(end 0.67945 -0.305054)
			(stroke
				(width 0.1)
				(type default)
			)
			(layer "B.Fab")
		)
		(fp_line
			(start 0.67945 -0.305054)
			(end 0.12065 -0.305054)
			(stroke
				(width 0.1)
				(type default)
			)
			(layer "B.Fab")
		)
		(fp_line
			(start 0.12065 0.3048)
			(end 0.67945 0.3048)
			(stroke
				(width 0.1)
				(type default)
			)
			(layer "B.Fab")
		)
		(fp_line
			(start 0.12065 0.2794)
			(end 0.12065 0.3048)
			(stroke
				(width 0.1)
				(type default)
			)
			(layer "B.Fab")
		)
		(fp_line
			(start 0.12065 -0.2794)
			(end -0.12065 -0.2794)
			(stroke
				(width 0.1)
				(type default)
			)
			(layer "B.Fab")
		)
		(fp_line
			(start 0.12065 -0.305054)
			(end 0.12065 -0.2794)
			(stroke
				(width 0.1)
				(type default)
			)
			(layer "B.Fab")
		)
		(fp_line
			(start -0.120396 0.3048)
			(end -0.120396 0.2794)
			(stroke
				(width 0.1)
				(type default)
			)
			(layer "B.Fab")
		)
		(fp_line
			(start -0.120396 0.2794)
			(end 0.12065 0.2794)
			(stroke
				(width 0.1)
				(type default)
			)
			(layer "B.Fab")
		)
		(fp_line
			(start -0.12065 -0.2794)
			(end -0.12065 -0.3048)
			(stroke
				(width 0.1)
				(type default)
			)
			(layer "B.Fab")
		)
		(fp_line
			(start -0.12065 -0.3048)
			(end -0.67945 -0.3048)
			(stroke
				(width 0.1)
				(type default)
			)
			(layer "B.Fab")
		)
		(fp_line
			(start -0.67945 0.3048)
			(end -0.120396 0.3048)
			(stroke
				(width 0.1)
				(type default)
			)
			(layer "B.Fab")
		)
		(fp_line
			(start -0.67945 -0.3048)
			(end -0.67945 0.3048)
			(stroke
				(width 0.1)
				(type default)
			)
			(layer "B.Fab")
		)
		(pad "1" smd circle
			(at 0.40005 0)
			(size 0 0)
			(layers "B.Cu" "B.Mask" "B.Paste")
			(net "P1V8_CPU0_RT_1D_ADC_MAM")
		)
		(pad "2" smd circle
			(at -0.40005 0)
			(size 0 0)
			(layers "B.Cu" "B.Mask" "B.Paste")
			(net "GND")
		)
	)
)
